(kicad_pcb
	(version 20260206)
	(generator "pcbnew")
	(generator_version "10.0")
	(general
		(thickness 1.6)
		(legacy_teardrops no)
	)
	(paper "A4")
	(title_block
		(title "Bryce Canyon_R.DPB_16317-1_OCP.brd")
		(comment 1 "Bryce Canyon / footprints 1686-1693 of 2099")
	)
	(layers
		(0 "F.Cu" signal "TOP")
		(4 "In1.Cu" signal "L2GND")
		(6 "In2.Cu" signal "L3")
		(8 "In3.Cu" signal "L4VCC")
		(10 "In4.Cu" signal "L5VCC")
		(12 "In5.Cu" signal "L6")
		(14 "In6.Cu" signal "L7GND")
		(2 "B.Cu" signal "BOTTOM")
		(9 "F.Adhes" user "F.Adhesive")
		(11 "B.Adhes" user "B.Adhesive")
		(13 "F.Paste" user "Package Geometry/Pastemask Top")
		(15 "B.Paste" user "Package Geometry/Pastemask Bottom")
		(5 "F.SilkS" user "Ref Des/Silkscreen Top")
		(7 "B.SilkS" user "Ref Des/Silkscreen Bottom")
		(1 "F.Mask" user "Board Geometry/Soldermask Top")
		(3 "B.Mask" user "Board Geometry/Soldermask Bottom")
		(17 "Dwgs.User" user "User.Drawings")
		(19 "Cmts.User" user "User.Comments")
		(21 "Eco1.User" user "User.Eco1")
		(23 "Eco2.User" user "User.Eco2")
		(25 "Edge.Cuts" user "Board Geometry/Outline")
		(27 "Margin" user)
		(31 "F.CrtYd" user "Package Geometry/Place Bound Top")
		(29 "B.CrtYd" user "Package Geometry/Place Bound Bottom")
		(35 "F.Fab" user "Ref Des/Assembly Top")
		(33 "B.Fab" user "Ref Des/Assembly Bottom")
	)
	(footprint ""
		(layer "F.Cu")
		(at 54.102 -13.0048 -90)
		(property "Reference" "D25"
			(at 0 0 270)
			(layer "F.SilkS")
			(hide yes)
			(effects
				(font
					(size 1.27 1.27)
				)
			)
		)
		(property "Value" "RB551V30-GP"
			(at 0 -6.7818 270)
			(unlocked yes)
			(layer "F.Fab")
			(hide yes)
			(effects
				(font
					(size 1.016 1.016)
					(thickness 0.1524)
				)
			)
		)
		(property "Device Type" "SOD323AKH38"
			(at 0 -8.6868 270)
			(unlocked yes)
			(layer "F.Fab")
			(hide yes)
			(effects
				(font
					(size 1.016 1.016)
					(thickness 0.1524)
				)
			)
		)
		(duplicate_pad_numbers_are_jumpers no)
		(fp_line
			(start -0.889 2.159)
			(end -0.889 -1.9304)
			(stroke
				(width 0.1524)
				(type default)
			)
			(layer "F.SilkS")
		)
		(fp_line
			(start 0.889 2.159)
			(end -0.889 2.159)
			(stroke
				(width 0.1524)
				(type default)
			)
			(layer "F.SilkS")
		)
		(fp_line
			(start 0.762 2.0574)
			(end -0.762 2.0574)
			(stroke
				(width 0.508)
				(type default)
			)
			(layer "F.SilkS")
		)
		(fp_line
			(start -0.889 -1.9304)
			(end 0.889 -1.9304)
			(stroke
				(width 0.1524)
				(type default)
			)
			(layer "F.SilkS")
		)
		(fp_line
			(start 0.889 -1.9304)
			(end 0.889 2.159)
			(stroke
				(width 0.1524)
				(type default)
			)
			(layer "F.SilkS")
		)
		(fp_rect
			(start -1.016 2.3114)
			(end 1.016 -2.0066)
			(stroke
				(width 0)
				(type default)
			)
			(fill no)
			(layer "F.CrtYd")
		)
		(fp_poly
			(pts
				(xy -1.016 -2.0066) (xy 1.016 -2.0066) (xy 1.016 2.3114) (xy -1.016 2.3114)
			)
			(stroke
				(width 0)
				(type default)
			)
			(fill no)
			(layer "F.Fab")
		)
		(pad "A" smd rect
			(at 0 -1.143 270)
			(size 0.5588 1.016)
			(layers "F.Cu" "F.Mask" "F.Paste")
			(net "SW_HDD_R25")
		)
		(pad "K" smd rect
			(at 0 1.143 270)
			(size 0.5588 1.016)
			(layers "F.Cu" "F.Mask" "F.Paste")
			(net "SW_HDD_N25")
		)
	)
	(footprint ""
		(layer "F.Cu")
		(at 333.502 -274.955 180)
		(property "Reference" "C113"
			(at 0 0 180)
			(layer "F.SilkS")
			(hide yes)
			(effects
				(font
					(size 1.27 1.27)
				)
			)
		)
		(property "Value" "SC4D7U25V5KX-1-GP"
			(at -0.0762 -6.1214 180)
			(unlocked yes)
			(layer "F.Fab")
			(hide yes)
			(effects
				(font
					(size 1.016 1.016)
					(thickness 0.1524)
				)
			)
		)
		(property "Device Type" "C805H58"
			(at -0.0762 -8.1534 180)
			(unlocked yes)
			(layer "F.Fab")
			(hide yes)
			(effects
				(font
					(size 1.016 1.016)
					(thickness 0.1524)
				)
			)
		)
		(duplicate_pad_numbers_are_jumpers no)
		(fp_line
			(start 0.635 0)
			(end -0.635 0)
			(stroke
				(width 0.508)
				(type default)
			)
			(layer "F.SilkS")
		)
		(fp_rect
			(start -0.9652 1.778)
			(end 0.9652 -1.778)
			(stroke
				(width 0)
				(type default)
			)
			(fill no)
			(layer "F.CrtYd")
		)
		(fp_poly
			(pts
				(xy -0.9652 -1.778) (xy 0.9652 -1.778) (xy 0.9652 1.778) (xy -0.9652 1.778)
			)
			(stroke
				(width 0)
				(type default)
			)
			(fill no)
			(layer "F.Fab")
		)
		(pad "1" smd rect
			(at 0 -0.9652 180)
			(size 1.397 1.143)
			(layers "F.Cu" "F.Mask" "F.Paste")
			(net "P12V_HDD6")
		)
		(pad "2" smd rect
			(at 0 0.9652 180)
			(size 1.397 1.143)
			(layers "F.Cu" "F.Mask" "F.Paste")
			(net "GND")
		)
	)
	(footprint ""
		(layer "F.Cu")
		(at 50.419 -150.622 90)
		(property "Reference" "R370"
			(at 0 0 90)
			(layer "F.SilkS")
			(hide yes)
			(effects
				(font
					(size 1.27 1.27)
				)
			)
		)
		(property "Value" "2R6F-GP"
			(at -0.0508 -4.8514 90)
			(unlocked yes)
			(layer "F.Fab")
			(hide yes)
			(effects
				(font
					(size 1.016 1.016)
					(thickness 0.1524)
				)
			)
		)
		(property "Device Type" "R1206H26"
			(at 0 -6.3754 90)
			(unlocked yes)
			(layer "F.Fab")
			(hide yes)
			(effects
				(font
					(size 1.016 1.016)
					(thickness 0.1524)
				)
			)
		)
		(duplicate_pad_numbers_are_jumpers no)
		(fp_line
			(start 1.016 -2.2352)
			(end 1.016 2.2352)
			(stroke
				(width 0.1524)
				(type default)
			)
			(layer "F.SilkS")
		)
		(fp_line
			(start -1.016 -2.2352)
			(end 1.016 -2.2352)
			(stroke
				(width 0.1524)
				(type default)
			)
			(layer "F.SilkS")
		)
		(fp_line
			(start 1.016 2.2352)
			(end -1.016 2.2352)
			(stroke
				(width 0.1524)
				(type default)
			)
			(layer "F.SilkS")
		)
		(fp_line
			(start -1.016 2.2352)
			(end -1.016 -2.2352)
			(stroke
				(width 0.1524)
				(type default)
			)
			(layer "F.SilkS")
		)
		(fp_rect
			(start -1.0922 2.3114)
			(end 1.0922 -2.3114)
			(stroke
				(width 0)
				(type default)
			)
			(fill no)
			(layer "F.CrtYd")
		)
		(fp_poly
			(pts
				(xy -1.0922 -2.3114) (xy 1.0922 -2.3114) (xy 1.0922 2.3114) (xy -1.0922 2.3114)
			)
			(stroke
				(width 0)
				(type default)
			)
			(fill no)
			(layer "F.Fab")
		)
		(pad "1" smd rect
			(at 0 -1.397 90)
			(size 1.651 1.27)
			(layers "F.Cu" "F.Mask" "F.Paste")
			(net "P12V_HDD13")
		)
		(pad "2" smd rect
			(at 0 1.397 90)
			(size 1.651 1.27)
			(layers "F.Cu" "F.Mask" "F.Paste")
			(net "12V_PRE_13")
		)
	)
	(footprint ""
		(layer "F.Cu")
		(at 239.071658 -133.101842 90)
		(property "Reference" "R417"
			(at 0 0 90)
			(layer "F.SilkS")
			(hide yes)
			(effects
				(font
					(size 1.27 1.27)
				)
			)
		)
		(property "Value" "1KR2J-1-GP"
			(at 0.064008 -3.993896 90)
			(unlocked yes)
			(layer "F.Fab")
			(hide yes)
			(effects
				(font
					(size 1.016 1.016)
					(thickness 0.1524)
				)
			)
		)
		(property "Device Type" "R402H16"
			(at 0.064008 -5.517896 90)
			(unlocked yes)
			(layer "F.Fab")
			(hide yes)
			(effects
				(font
					(size 1.016 1.016)
					(thickness 0.1524)
				)
			)
		)
		(duplicate_pad_numbers_are_jumpers no)
		(fp_line
			(start 0.508 -0.9398)
			(end -0.508 -0.9398)
			(stroke
				(width 0.1524)
				(type default)
			)
			(layer "F.SilkS")
		)
		(fp_line
			(start -0.508 -0.9398)
			(end -0.508 0.9398)
			(stroke
				(width 0.1524)
				(type default)
			)
			(layer "F.SilkS")
		)
		(fp_rect
			(start -0.508 0.9398)
			(end 0.508 -0.9398)
			(stroke
				(width 0)
				(type default)
			)
			(fill no)
			(layer "F.CrtYd")
		)
		(fp_rect
			(start -0.508 0.9398)
			(end 0.508 -0.9398)
			(stroke
				(width 0)
				(type default)
			)
			(fill no)
			(layer "F.Fab")
		)
		(pad "1" smd custom
			(at 0 -0.4445 90)
			(size 0.1397 0.1397)
			(layers "F.Cu" "F.Mask" "F.Paste")
			(net "P3V3_STBY_B")
			(options
				(clearance outline)
				(anchor circle)
			)
			(primitives
				(gr_poly
					(pts
						(arc
							(start -0.1778 -0.2794)
							(mid -0.249642 -0.249642)
							(end -0.2794 -0.1778)
						)
						(arc
							(start -0.2794 0.1778)
							(mid -0.249642 0.249642)
							(end -0.1778 0.2794)
						)
						(arc
							(start 0.1778 0.2794)
							(mid 0.249642 0.249642)
							(end 0.2794 0.1778)
						)
						(arc
							(start 0.2794 -0.1778)
							(mid 0.249642 -0.249642)
							(end 0.1778 -0.2794)
						)
					)
					(width 0)
					(fill yes)
				)
			)
		)
		(pad "2" smd custom
			(at 0 0.4445 90)
			(size 0.1397 0.1397)
			(layers "F.Cu" "F.Mask" "F.Paste")
			(net "I2C_DPB_B_SCL_BUF")
			(options
				(clearance outline)
				(anchor circle)
			)
			(primitives
				(gr_poly
					(pts
						(arc
							(start -0.1778 -0.2794)
							(mid -0.249642 -0.249642)
							(end -0.2794 -0.1778)
						)
						(arc
							(start -0.2794 0.1778)
							(mid -0.249642 0.249642)
							(end -0.1778 0.2794)
						)
						(arc
							(start 0.1778 0.2794)
							(mid 0.249642 0.249642)
							(end 0.2794 0.1778)
						)
						(arc
							(start 0.2794 -0.1778)
							(mid 0.249642 -0.249642)
							(end 0.1778 -0.2794)
						)
					)
					(width 0)
					(fill yes)
				)
			)
		)
	)
	(footprint ""
		(layer "F.Cu")
		(at 370.205 -27.813 -90)
		(property "Reference" "R797"
			(at 0 0 270)
			(layer "F.SilkS")
			(hide yes)
			(effects
				(font
					(size 1.27 1.27)
				)
			)
		)
		(property "Value" "300KR2F-GP"
			(at 0.064008 -3.993896 270)
			(unlocked yes)
			(layer "F.Fab")
			(hide yes)
			(effects
				(font
					(size 1.016 1.016)
					(thickness 0.1524)
				)
			)
		)
		(property "Device Type" "R402H16"
			(at 0.064008 -5.517896 270)
			(unlocked yes)
			(layer "F.Fab")
			(hide yes)
			(effects
				(font
					(size 1.016 1.016)
					(thickness 0.1524)
				)
			)
		)
		(duplicate_pad_numbers_are_jumpers no)
		(fp_line
			(start -0.508 -0.9398)
			(end -0.508 0.9398)
			(stroke
				(width 0.1524)
				(type default)
			)
			(layer "F.SilkS")
		)
		(fp_line
			(start 0.508 -0.9398)
			(end -0.508 -0.9398)
			(stroke
				(width 0.1524)
				(type default)
			)
			(layer "F.SilkS")
		)
		(fp_rect
			(start -0.508 0.9398)
			(end 0.508 -0.9398)
			(stroke
				(width 0)
				(type default)
			)
			(fill no)
			(layer "F.CrtYd")
		)
		(fp_rect
			(start -0.508 0.9398)
			(end 0.508 -0.9398)
			(stroke
				(width 0)
				(type default)
			)
			(fill no)
			(layer "F.Fab")
		)
		(pad "1" smd custom
			(at 0 -0.4445 270)
			(size 0.1397 0.1397)
			(layers "F.Cu" "F.Mask" "F.Paste")
			(net "SW_HDD_N31")
			(options
				(clearance outline)
				(anchor circle)
			)
			(primitives
				(gr_poly
					(pts
						(arc
							(start -0.1778 -0.2794)
							(mid -0.249642 -0.249642)
							(end -0.2794 -0.1778)
						)
						(arc
							(start -0.2794 0.1778)
							(mid -0.249642 0.249642)
							(end -0.1778 0.2794)
						)
						(arc
							(start 0.1778 0.2794)
							(mid 0.249642 0.249642)
							(end 0.2794 0.1778)
						)
						(arc
							(start 0.2794 -0.1778)
							(mid 0.249642 -0.249642)
							(end 0.1778 -0.2794)
						)
					)
					(width 0)
					(fill yes)
				)
			)
		)
		(pad "2" smd custom
			(at 0 0.4445 270)
			(size 0.1397 0.1397)
			(layers "F.Cu" "F.Mask" "F.Paste")
			(net "P12V_B")
			(options
				(clearance outline)
				(anchor circle)
			)
			(primitives
				(gr_poly
					(pts
						(arc
							(start -0.1778 -0.2794)
							(mid -0.249642 -0.249642)
							(end -0.2794 -0.1778)
						)
						(arc
							(start -0.2794 0.1778)
							(mid -0.249642 0.249642)
							(end -0.1778 0.2794)
						)
						(arc
							(start 0.1778 0.2794)
							(mid 0.249642 0.249642)
							(end 0.2794 0.1778)
						)
						(arc
							(start 0.2794 -0.1778)
							(mid 0.249642 -0.249642)
							(end 0.1778 -0.2794)
						)
					)
					(width 0)
					(fill yes)
				)
			)
		)
	)
	(footprint ""
		(layer "F.Cu")
		(at 463.411824 -223.027748 90)
		(property "Reference" "C661"
			(at 0 0 90)
			(layer "F.SilkS")
			(hide yes)
			(effects
				(font
					(size 1.27 1.27)
				)
			)
		)
		(property "Value" "SCD1U16V2KX-3GP"
			(at 1.1811 -2.7051 90)
			(unlocked yes)
			(layer "F.Fab")
			(hide yes)
			(effects
				(font
					(size 1.016 1.016)
					(thickness 0.1524)
				)
			)
		)
		(property "Device Type" "C402H22"
			(at 1.1811 -4.2291 90)
			(unlocked yes)
			(layer "F.Fab")
			(hide yes)
			(effects
				(font
					(size 1.016 1.016)
					(thickness 0.1524)
				)
			)
		)
		(duplicate_pad_numbers_are_jumpers no)
		(fp_rect
			(start -0.4318 0.9525)
			(end 0.4318 -0.9525)
			(stroke
				(width 0)
				(type default)
			)
			(fill no)
			(layer "F.CrtYd")
		)
		(fp_rect
			(start -0.4318 0.9525)
			(end 0.4318 -0.9525)
			(stroke
				(width 0)
				(type default)
			)
			(fill no)
			(layer "F.Fab")
		)
		(pad "1" smd custom
			(at 0 -0.4445 90)
			(size 0.1524 0.1524)
			(layers "F.Cu" "F.Mask" "F.Paste")
			(net "P5V_B_3_VBST_RC")
			(options
				(clearance outline)
				(anchor circle)
			)
			(primitives
				(gr_poly
					(pts
						(arc
							(start 0.3048 -0.2032)
							(mid 0.275042 -0.275042)
							(end 0.2032 -0.3048)
						)
						(arc
							(start -0.2032 -0.3048)
							(mid -0.275042 -0.275042)
							(end -0.3048 -0.2032)
						)
						(arc
							(start -0.3048 0.2032)
							(mid -0.275042 0.275042)
							(end -0.2032 0.3048)
						)
						(arc
							(start 0.2032 0.3048)
							(mid 0.275042 0.275042)
							(end 0.3048 0.2032)
						)
					)
					(width 0)
					(fill yes)
				)
			)
		)
		(pad "2" smd custom
			(at 0 0.4445 90)
			(size 0.1524 0.1524)
			(layers "F.Cu" "F.Mask" "F.Paste")
			(net "P5V_B_3_LL")
			(options
				(clearance outline)
				(anchor circle)
			)
			(primitives
				(gr_poly
					(pts
						(arc
							(start 0.3048 -0.2032)
							(mid 0.275042 -0.275042)
							(end 0.2032 -0.3048)
						)
						(arc
							(start -0.2032 -0.3048)
							(mid -0.275042 -0.275042)
							(end -0.3048 -0.2032)
						)
						(arc
							(start -0.3048 0.2032)
							(mid -0.275042 0.275042)
							(end -0.2032 0.3048)
						)
						(arc
							(start 0.2032 0.3048)
							(mid 0.275042 0.275042)
							(end 0.3048 0.2032)
						)
					)
					(width 0)
					(fill yes)
				)
			)
		)
	)
	(footprint ""
		(layer "F.Cu")
		(at 107.099862 -23.999952)
		(property "Reference" ""
			(at 0 0 0)
			(layer "F.SilkS")
			(hide yes)
			(effects
				(font
					(size 1.27 1.27)
				)
			)
		)
		(property "Value" "*"
			(at -6.3373 -0.4572 0)
			(unlocked yes)
			(layer "F.Fab")
			(hide yes)
			(effects
				(font
					(size 1.016 1.016)
					(thickness 0.1524)
				)
			)
		)
		(duplicate_pad_numbers_are_jumpers no)
		(fp_poly
			(pts
				(arc
					(start 5.0673 0)
					(mid -5.0673 0)
					(end 5.0673 0)
				)
			)
			(stroke
				(width 0)
				(type default)
			)
			(fill no)
			(layer "B.CrtYd")
		)
		(fp_poly
			(pts
				(arc
					(start 5.0673 0)
					(mid -5.0673 0)
					(end 5.0673 0)
				)
			)
			(stroke
				(width 0)
				(type default)
			)
			(fill no)
			(layer "F.CrtYd")
		)
		(fp_poly
			(pts
				(arc
					(start 5.0673 0)
					(mid -5.0673 0)
					(end 5.0673 0)
				)
			)
			(stroke
				(width 0)
				(type default)
			)
			(fill no)
			(layer "B.Fab")
		)
		(fp_poly
			(pts
				(arc
					(start 5.0673 0)
					(mid -5.0673 0)
					(end 5.0673 0)
				)
			)
			(stroke
				(width 0)
				(type default)
			)
			(fill no)
			(layer "F.Fab")
		)
		(pad "1" thru_hole circle
			(at 0 0)
			(size 9.525 9.525)
			(drill 3.556)
			(layers "*.Cu" "*.Mask")
			(remove_unused_layers no)
			(net "Net_36")
			(clearance -2.4765)
			(thermal_gap 0.3048)
			(padstack
				(mode front_inner_back)
				(layer "Inner"
					(shape circle)
					(size 3.9624 3.9624)
					(clearance 0.3048)
				)
				(layer "B.Cu"
					(shape circle)
					(size 9.525 9.525)
					(clearance -2.4765)
				)
			)
		)
		(zone
			(layers "F.Cu" "B.Cu" "In1.Cu" "In2.Cu" "In3.Cu" "In4.Cu" "In5.Cu" "In6.Cu")
			(hatch none 0.5)
			(connect_pads
				(clearance 0)
			)
			(min_thickness 0.25)
			(keepout
				(tracks not_allowed)
				(vias allowed)
				(pads allowed)
				(copperpour not_allowed)
				(footprints allowed)
			)
			(placement
				(enabled no)
				(sheetname "")
			)
			(fill
				(thermal_gap 0.5)
				(thermal_bridge_width 0.5)
				(island_removal_mode 0)
			)
			(polygon
				(pts
					(arc
						(start 111.862362 -23.999952)
						(mid 102.337362 -23.999952)
						(end 111.862362 -23.999952)
					)
				)
			)
		)
	)
	(footprint ""
		(layer "F.Cu")
		(at 394.589 -44.958 180)
		(property "Reference" "C450"
			(at 0 0 180)
			(layer "F.SilkS")
			(hide yes)
			(effects
				(font
					(size 1.27 1.27)
				)
			)
		)
		(property "Value" "SC4D7U25V5KX-1-GP"
			(at -0.0762 -6.1214 180)
			(unlocked yes)
			(layer "F.Fab")
			(hide yes)
			(effects
				(font
					(size 1.016 1.016)
					(thickness 0.1524)
				)
			)
		)
		(property "Device Type" "C805H58"
			(at -0.0762 -8.1534 180)
			(unlocked yes)
			(layer "F.Fab")
			(hide yes)
			(effects
				(font
					(size 1.016 1.016)
					(thickness 0.1524)
				)
			)
		)
		(duplicate_pad_numbers_are_jumpers no)
		(fp_line
			(start 0.635 0)
			(end -0.635 0)
			(stroke
				(width 0.508)
				(type default)
			)
			(layer "F.SilkS")
		)
		(fp_rect
			(start -0.9652 1.778)
			(end 0.9652 -1.778)
			(stroke
				(width 0)
				(type default)
			)
			(fill no)
			(layer "F.CrtYd")
		)
		(fp_poly
			(pts
				(xy -0.9652 -1.778) (xy 0.9652 -1.778) (xy 0.9652 1.778) (xy -0.9652 1.778)
			)
			(stroke
				(width 0)
				(type default)
			)
			(fill no)
			(layer "F.Fab")
		)
		(pad "1" smd rect
			(at 0 -0.9652 180)
			(size 1.397 1.143)
			(layers "F.Cu" "F.Mask" "F.Paste")
			(net "P12V_HDD32")
		)
		(pad "2" smd rect
			(at 0 0.9652 180)
			(size 1.397 1.143)
			(layers "F.Cu" "F.Mask" "F.Paste")
			(net "GND")
		)
	)
)
